# BASEBOARD_FAB2 (Tioga Pass) — schematic netlist excerpt (pin names and nets, part order shuffled) for the footprints in the layout excerpt that follows; sources: Cadence DE-HDL packaged netlist, KiCad conversion of Wiwynn_Tioga_Pass_MB.brd

C3P20  CAP  0.22UF 16V 10% X7R  pkg 0402  page 107 : A = P3E_CPU0_PE1_SS_TXN<2> ; B = P3E_CPU0_PE1_PCH_TXN<2>
C25P83  CAP_A  0.1UF 16V 10% X7R  pkg 0402V  page 252 : A = P5V_VGA ; B = GND
C6N10  CAP  10UF 16V 10% X6S  pkg 0805  page 204 : A = VR_FET_SW_P12V_STBY_PVCCIN_CPU0 ; B = GND
C7W6  SC22U16V5MX-4-GP  20%  pkg SMD-BCG5  page 220 : \1\ = VR_FET_SW_P12V_STBY_PVDDQ_DEF ; \2\ = GND

(kicad_pcb
	(version 20260206)
	(generator "pcbnew")
	(generator_version "10.0")
	(general
		(thickness 1.6)
		(legacy_teardrops no)
	)
	(paper "A4")
	(title_block
		(title "Wiwynn_Tioga_Pass_MB.brd")
		(comment 1 "Tioga Pass / footprints 3971-3974 of 4770")
	)
	(layers
		(0 "F.Cu" signal "TOP")
		(4 "In1.Cu" signal "L2GND")
		(6 "In2.Cu" signal "L3")
		(8 "In3.Cu" signal "L4GND")
		(10 "In4.Cu" signal "L5")
		(12 "In5.Cu" signal "L6GND")
		(14 "In6.Cu" signal "L7VCC")
		(16 "In7.Cu" signal "L8VCC")
		(18 "In8.Cu" signal "L9GND")
		(20 "In9.Cu" signal "L10")
		(22 "In10.Cu" signal "L11GND")
		(24 "In11.Cu" signal "L12")
		(26 "In12.Cu" signal "L13GND")
		(2 "B.Cu" signal "BOTTOM")
		(9 "F.Adhes" user "F.Adhesive")
		(11 "B.Adhes" user "B.Adhesive")
		(13 "F.Paste" user "Package Geometry/Pastemask Top")
		(15 "B.Paste" user "Package Geometry/Pastemask Bottom")
		(5 "F.SilkS" user "Ref Des/Silkscreen Top")
		(7 "B.SilkS" user "Ref Des/Silkscreen Bottom")
		(1 "F.Mask" user "Board Geometry/Soldermask Top")
		(3 "B.Mask" user "Board Geometry/Soldermask Bottom")
		(17 "Dwgs.User" user "User.Drawings")
		(19 "Cmts.User" user "User.Comments")
		(21 "Eco1.User" user "User.Eco1")
		(23 "Eco2.User" user "User.Eco2")
		(25 "Edge.Cuts" user "Board Geometry/Outline")
		(27 "Margin" user)
		(31 "F.CrtYd" user "Package Geometry/Place Bound Top")
		(29 "B.CrtYd" user "Package Geometry/Place Bound Bottom")
		(35 "F.Fab" user "Ref Des/Assembly Top")
		(33 "B.Fab" user "Ref Des/Assembly Bottom")
	)
	(footprint ""
		(layer "B.Cu")
		(at 365.001302 -145.471642)
		(property "Reference" "C7W6"
			(at 0 0 0)
			(layer "B.SilkS")
			(hide yes)
			(effects
				(font
					(size 1.27 1.27)
				)
				(justify mirror)
			)
		)
		(property "Value" "*"
			(at 0.0762 -6.2357 0)
			(unlocked yes)
			(layer "B.Fab")
			(hide yes)
			(effects
				(font
					(size 1.27 1.016)
					(thickness 0.1524)
				)
				(justify mirror)
			)
		)
		(property "Device Type" "SC22U16V5MX-4-GP_SMD-BCG5-SC22A"
			(at 0.0762 -8.2677 0)
			(unlocked yes)
			(layer "B.Fab")
			(hide yes)
			(effects
				(font
					(size 1.27 1.016)
					(thickness 0.1524)
				)
				(justify mirror)
			)
		)
		(duplicate_pad_numbers_are_jumpers no)
		(fp_line
			(start -0.635 0)
			(end 0.635 0)
			(stroke
				(width 0.508)
				(type default)
			)
			(layer "B.SilkS")
		)
		(fp_rect
			(start 0.9652 1.778)
			(end -0.9652 -1.778)
			(stroke
				(width 0)
				(type default)
			)
			(fill no)
			(layer "B.CrtYd")
		)
		(fp_poly
			(pts
				(xy 0.9652 -1.778) (xy -0.9652 -1.778) (xy -0.9652 1.778) (xy 0.9652 1.778)
			)
			(stroke
				(width 0)
				(type default)
			)
			(fill no)
			(layer "B.Fab")
		)
		(pad "1" smd rect
			(at 0 -0.9652 180)
			(size 1.397 1.143)
			(layers "B.Cu" "B.Mask" "B.Paste")
			(net "VR_FET_SW_P12V_STBY_PVDDQ_DEF")
		)
		(pad "2" smd rect
			(at 0 0.9652 180)
			(size 1.397 1.143)
			(layers "B.Cu" "B.Mask" "B.Paste")
			(net "GND")
		)
	)
	(footprint ""
		(layer "B.Cu")
		(at 197.848728 -90.838782 90)
		(property "Reference" "C6N10"
			(at 0 0 90)
			(layer "B.SilkS")
			(hide yes)
			(effects
				(font
					(size 1.27 1.27)
				)
				(justify mirror)
			)
		)
		(property "Value" ""
			(at 0 0 90)
			(layer "B.Fab")
			(effects
				(font
					(size 1.27 1.27)
				)
				(justify mirror)
			)
		)
		(duplicate_pad_numbers_are_jumpers no)
		(fp_rect
			(start 0.7239 1.9939)
			(end -0.7239 -0.2159)
			(stroke
				(width 0)
				(type default)
			)
			(fill no)
			(layer "B.CrtYd")
		)
		(fp_line
			(start 0.7239 -0.2159)
			(end 0.7239 1.9939)
			(stroke
				(width 0.1)
				(type default)
			)
			(layer "B.Fab")
		)
		(fp_line
			(start -0.7239 -0.2159)
			(end 0.7239 -0.2159)
			(stroke
				(width 0.1)
				(type default)
			)
			(layer "B.Fab")
		)
		(fp_line
			(start 0.7239 1.9939)
			(end -0.7239 1.9939)
			(stroke
				(width 0.1)
				(type default)
			)
			(layer "B.Fab")
		)
		(fp_line
			(start -0.7239 1.9939)
			(end -0.7239 -0.2159)
			(stroke
				(width 0.1)
				(type default)
			)
			(layer "B.Fab")
		)
		(pad "1" smd rect
			(at 0 0 270)
			(size 1.27 1.016)
			(layers "B.Cu" "B.Mask" "B.Paste")
			(net "VR_FET_SW_P12V_STBY_PVCCIN_CPU0")
		)
		(pad "2" smd rect
			(at 0 1.778 270)
			(size 1.27 1.016)
			(layers "B.Cu" "B.Mask" "B.Paste")
			(net "GND")
		)
		(zone
			(layer "B.Cu")
			(hatch none 0.5)
			(connect_pads
				(clearance 0)
			)
			(min_thickness 0.25)
			(keepout
				(tracks not_allowed)
				(vias allowed)
				(pads allowed)
				(copperpour not_allowed)
				(footprints allowed)
			)
			(placement
				(enabled no)
				(sheetname "")
			)
			(fill
				(thermal_gap 0.5)
				(thermal_bridge_width 0.5)
				(island_removal_mode 0)
			)
			(polygon
				(pts
					(xy 199.118728 -91.473782) (xy 198.356728 -91.473782) (xy 198.356728 -90.203782) (xy 199.118728 -90.203782)
				)
			)
		)
	)
	(footprint ""
		(layer "B.Cu")
		(at 345.832176 -77.694536 180)
		(property "Reference" "C3P20"
			(at 0 0 0)
			(layer "B.SilkS")
			(hide yes)
			(effects
				(font
					(size 1.27 1.27)
				)
				(justify mirror)
			)
		)
		(property "Value" ""
			(at 0 0 0)
			(layer "B.Fab")
			(effects
				(font
					(size 1.27 1.27)
				)
				(justify mirror)
			)
		)
		(duplicate_pad_numbers_are_jumpers no)
		(fp_poly
			(pts
				(xy -0.3048 -0.1016) (xy -0.3048 0.9906) (xy 0.3048 0.9906) (xy 0.3048 -0.1016)
			)
			(stroke
				(width 0)
				(type default)
			)
			(fill no)
			(layer "B.CrtYd")
		)
		(fp_line
			(start 0.3048 0.9906)
			(end -0.3048 0.9906)
			(stroke
				(width 0.1)
				(type default)
			)
			(layer "B.Fab")
		)
		(fp_line
			(start 0.3048 -0.1016)
			(end 0.3048 0.9906)
			(stroke
				(width 0.1)
				(type default)
			)
			(layer "B.Fab")
		)
		(fp_line
			(start -0.3048 0.9906)
			(end -0.3048 -0.1016)
			(stroke
				(width 0.1)
				(type default)
			)
			(layer "B.Fab")
		)
		(fp_line
			(start -0.3048 -0.1016)
			(end 0.3048 -0.1016)
			(stroke
				(width 0.1)
				(type default)
			)
			(layer "B.Fab")
		)
		(pad "1" smd rect
			(at 0 0)
			(size 0.508 0.508)
			(layers "B.Cu" "B.Mask" "B.Paste")
			(net "P3E_CPU0_PE1_SS_TXN<2>")
		)
		(pad "2" smd rect
			(at 0 0.889)
			(size 0.508 0.508)
			(layers "B.Cu" "B.Mask" "B.Paste")
			(net "P3E_CPU0_PE1_PCH_TXN<2>")
		)
		(zone
			(layer "B.Cu")
			(hatch none 0.5)
			(connect_pads
				(clearance 0)
			)
			(min_thickness 0.25)
			(keepout
				(tracks allowed)
				(vias not_allowed)
				(pads allowed)
				(copperpour not_allowed)
				(footprints allowed)
			)
			(placement
				(enabled no)
				(sheetname "")
			)
			(fill
				(thermal_gap 0.5)
				(thermal_bridge_width 0.5)
				(island_removal_mode 0)
			)
			(polygon
				(pts
					(xy 345.578176 -77.948536) (xy 346.086176 -77.948536) (xy 346.086176 -78.329536) (xy 345.578176 -78.329536)
				)
			)
		)
	)
	(footprint ""
		(layer "B.Cu")
		(at 490.9058 -51.64709 180)
		(property "Reference" "C25P83"
			(at 0.8382 -0.67818 180)
			(unlocked yes)
			(layer "B.SilkS")
			(effects
				(font
					(size 0.4064 0.254)
					(thickness 0.1524)
				)
				(justify left mirror)
			)
		)
		(property "Value" ""
			(at 0 0 0)
			(layer "B.Fab")
			(effects
				(font
					(size 1.27 1.27)
				)
				(justify mirror)
			)
		)
		(duplicate_pad_numbers_are_jumpers no)
		(fp_poly
			(pts
				(xy -0.3048 -0.1016) (xy -0.3048 0.9906) (xy 0.3048 0.9906) (xy 0.3048 -0.1016)
			)
			(stroke
				(width 0)
				(type default)
			)
			(fill no)
			(layer "B.CrtYd")
		)
		(fp_line
			(start 0.3048 0.9906)
			(end -0.3048 0.9906)
			(stroke
				(width 0.1)
				(type default)
			)
			(layer "B.Fab")
		)
		(fp_line
			(start 0.3048 -0.1016)
			(end 0.3048 0.9906)
			(stroke
				(width 0.1)
				(type default)
			)
			(layer "B.Fab")
		)
		(fp_line
			(start -0.3048 0.9906)
			(end -0.3048 -0.1016)
			(stroke
				(width 0.1)
				(type default)
			)
			(layer "B.Fab")
		)
		(fp_line
			(start -0.3048 -0.1016)
			(end 0.3048 -0.1016)
			(stroke
				(width 0.1)
				(type default)
			)
			(layer "B.Fab")
		)
		(pad "1" smd rect
			(at 0 0)
			(size 0.508 0.508)
			(layers "B.Cu" "B.Mask" "B.Paste")
			(net "P5V_VGA")
		)
		(pad "2" smd rect
			(at 0 0.889)
			(size 0.508 0.508)
			(layers "B.Cu" "B.Mask" "B.Paste")
			(net "GND")
		)
		(zone
			(layer "B.Cu")
			(hatch none 0.5)
			(connect_pads
				(clearance 0)
			)
			(min_thickness 0.25)
			(keepout
				(tracks not_allowed)
				(vias allowed)
				(pads allowed)
				(copperpour not_allowed)
				(footprints allowed)
			)
			(placement
				(enabled no)
				(sheetname "")
			)
			(fill
				(thermal_gap 0.5)
				(thermal_bridge_width 0.5)
				(island_removal_mode 0)
			)
			(polygon
				(pts
					(xy 490.6518 -52.28209) (xy 491.1598 -52.28209) (xy 491.1598 -51.90109) (xy 490.6518 -51.90109)
				)
			)
		)
		(zone
			(layer "B.Cu")
			(hatch none 0.5)
			(connect_pads
				(clearance 0)
			)
			(min_thickness 0.25)
			(keepout
				(tracks allowed)
				(vias not_allowed)
				(pads allowed)
				(copperpour not_allowed)
				(footprints allowed)
			)
			(placement
				(enabled no)
				(sheetname "")
			)
			(fill
				(thermal_gap 0.5)
				(thermal_bridge_width 0.5)
				(island_removal_mode 0)
			)
			(polygon
				(pts
					(xy 490.6518 -51.90109) (xy 491.1598 -51.90109) (xy 491.1598 -52.28209) (xy 490.6518 -52.28209)
				)
			)
		)
	)
)
